(kicad_pcb
	(version 20260206)
	(generator "pcbnew")
	(generator_version "10.0")
	(general
		(thickness 1.6)
		(legacy_teardrops no)
	)
	(paper "A4")
	(title_block
		(title "01162023_DA0F0TEBIF0_F0T_Expander_BD_F_brd_V02_OCP.brd")
		(comment 1 "Grand Teton / footprints 890-897 of 9728")
	)
	(layers
		(0 "F.Cu" signal "TOP")
		(4 "In1.Cu" signal "GND")
		(6 "In2.Cu" signal "VCC")
		(8 "In3.Cu" signal "VCC1")
		(10 "In4.Cu" signal "GND1")
		(12 "In5.Cu" signal "IN1")
		(14 "In6.Cu" signal "GND2")
		(16 "In7.Cu" signal "IN2")
		(18 "In8.Cu" signal "GND3")
		(20 "In9.Cu" signal "IN3")
		(22 "In10.Cu" signal "GND4")
		(24 "In11.Cu" signal "IN4")
		(26 "In12.Cu" signal "GND5")
		(28 "In13.Cu" signal "IN5")
		(30 "In14.Cu" signal "GND6")
		(32 "In15.Cu" signal "IN6")
		(34 "In16.Cu" signal "GND7")
		(2 "B.Cu" signal "BOTTOM")
		(9 "F.Adhes" user "F.Adhesive")
		(11 "B.Adhes" user "B.Adhesive")
		(13 "F.Paste" user "Package Geometry/Pastemask Top")
		(15 "B.Paste" user "Package Geometry/Pastemask Bottom")
		(5 "F.SilkS" user "Ref Des/Silkscreen Top")
		(7 "B.SilkS" user "Ref Des/Silkscreen Bottom")
		(1 "F.Mask" user "Board Geometry/Soldermask Top")
		(3 "B.Mask" user "Board Geometry/Soldermask Bottom")
		(17 "Dwgs.User" user "User.Drawings")
		(19 "Cmts.User" user "User.Comments")
		(21 "Eco1.User" user "User.Eco1")
		(23 "Eco2.User" user "User.Eco2")
		(25 "Edge.Cuts" user "Board Geometry/Outline")
		(27 "Margin" user)
		(31 "F.CrtYd" user "Package Geometry/Place Bound Top")
		(29 "B.CrtYd" user "Package Geometry/Place Bound Bottom")
		(35 "F.Fab" user "Ref Des/Assembly Top")
		(33 "B.Fab" user "Ref Des/Assembly Bottom")
	)
	(footprint ""
		(layer "F.Cu")
		(at 271.480534 -102.888796)
		(property "Reference" "C481"
			(at 0 0 0)
			(layer "F.SilkS")
			(hide yes)
			(effects
				(font
					(size 1.27 1.27)
				)
			)
		)
		(property "Value" ""
			(at 0 0 0)
			(layer "F.Fab")
			(effects
				(font
					(size 1.27 1.27)
				)
			)
		)
		(duplicate_pad_numbers_are_jumpers no)
		(fp_line
			(start -0.299974 -0.150114)
			(end 0.299974 -0.150114)
			(stroke
				(width 0.1)
				(type default)
			)
			(layer "F.Fab")
		)
		(fp_line
			(start -0.299974 0.150114)
			(end -0.299974 -0.150114)
			(stroke
				(width 0.1)
				(type default)
			)
			(layer "F.Fab")
		)
		(fp_line
			(start 0.299974 -0.150114)
			(end 0.299974 0.150114)
			(stroke
				(width 0.1)
				(type default)
			)
			(layer "F.Fab")
		)
		(fp_line
			(start 0.299974 0.150114)
			(end -0.299974 0.150114)
			(stroke
				(width 0.1)
				(type default)
			)
			(layer "F.Fab")
		)
		(pad "1" smd rect
			(at -0.2667 0)
			(size 0.3048 0.381)
			(layers "F.Cu" "F.Mask" "F.Paste")
			(net "P5E_PEX2_STN1_TX_DP<18>")
		)
		(pad "2" smd rect
			(at 0.2667 0)
			(size 0.3048 0.381)
			(layers "F.Cu" "F.Mask" "F.Paste")
			(net "P5E_PEX2_STN1_TX_C_DP<18>")
		)
	)
	(footprint ""
		(layer "F.Cu")
		(at 56.155336 -376.29592 90)
		(property "Reference" "C4013"
			(at 0 0 90)
			(layer "F.SilkS")
			(hide yes)
			(effects
				(font
					(size 1.27 1.27)
				)
			)
		)
		(property "Value" ""
			(at 0 0 90)
			(layer "F.Fab")
			(effects
				(font
					(size 1.27 1.27)
				)
			)
		)
		(duplicate_pad_numbers_are_jumpers no)
		(fp_line
			(start 0.7874 -0.4064)
			(end 0.7874 0.4064)
			(stroke
				(width 0.1524)
				(type default)
			)
			(layer "F.SilkS")
		)
		(fp_line
			(start -0.7874 -0.4064)
			(end 0.7874 -0.4064)
			(stroke
				(width 0.1524)
				(type default)
			)
			(layer "F.SilkS")
		)
		(fp_line
			(start 0.7874 0.4064)
			(end -0.7874 0.4064)
			(stroke
				(width 0.1524)
				(type default)
			)
			(layer "F.SilkS")
		)
		(fp_line
			(start -0.7874 0.4064)
			(end -0.7874 -0.4064)
			(stroke
				(width 0.1524)
				(type default)
			)
			(layer "F.SilkS")
		)
		(fp_line
			(start -0.12065 -0.305054)
			(end -0.12065 -0.2794)
			(stroke
				(width 0.1)
				(type default)
			)
			(layer "F.Fab")
		)
		(fp_line
			(start -0.67945 -0.305054)
			(end -0.12065 -0.305054)
			(stroke
				(width 0.1)
				(type default)
			)
			(layer "F.Fab")
		)
		(fp_line
			(start 0.67945 -0.3048)
			(end 0.67945 0.3048)
			(stroke
				(width 0.1)
				(type default)
			)
			(layer "F.Fab")
		)
		(fp_line
			(start 0.12065 -0.3048)
			(end 0.67945 -0.3048)
			(stroke
				(width 0.1)
				(type default)
			)
			(layer "F.Fab")
		)
		(fp_line
			(start 0.12065 -0.2794)
			(end 0.12065 -0.3048)
			(stroke
				(width 0.1)
				(type default)
			)
			(layer "F.Fab")
		)
		(fp_line
			(start -0.12065 -0.2794)
			(end 0.12065 -0.2794)
			(stroke
				(width 0.1)
				(type default)
			)
			(layer "F.Fab")
		)
		(fp_line
			(start 0.120396 0.2794)
			(end -0.12065 0.2794)
			(stroke
				(width 0.1)
				(type default)
			)
			(layer "F.Fab")
		)
		(fp_line
			(start -0.12065 0.2794)
			(end -0.12065 0.3048)
			(stroke
				(width 0.1)
				(type default)
			)
			(layer "F.Fab")
		)
		(fp_line
			(start 0.67945 0.3048)
			(end 0.120396 0.3048)
			(stroke
				(width 0.1)
				(type default)
			)
			(layer "F.Fab")
		)
		(fp_line
			(start 0.120396 0.3048)
			(end 0.120396 0.2794)
			(stroke
				(width 0.1)
				(type default)
			)
			(layer "F.Fab")
		)
		(fp_line
			(start -0.12065 0.3048)
			(end -0.67945 0.3048)
			(stroke
				(width 0.1)
				(type default)
			)
			(layer "F.Fab")
		)
		(fp_line
			(start -0.67945 0.3048)
			(end -0.67945 -0.305054)
			(stroke
				(width 0.1)
				(type default)
			)
			(layer "F.Fab")
		)
		(pad "1" smd circle
			(at -0.40005 0 90)
			(size 0 0)
			(layers "F.Cu" "F.Mask" "F.Paste")
			(net "GND")
		)
		(pad "2" smd circle
			(at 0.40005 0 90)
			(size 0 0)
			(layers "F.Cu" "F.Mask" "F.Paste")
			(net "GPU_BASE_PWR_GD")
		)
	)
	(footprint ""
		(layer "F.Cu")
		(at 361.188 -175.006 180)
		(property "Reference" "R4709"
			(at 0 0 180)
			(layer "F.SilkS")
			(hide yes)
			(effects
				(font
					(size 1.27 1.27)
				)
			)
		)
		(property "Value" ""
			(at 0 0 180)
			(layer "F.Fab")
			(effects
				(font
					(size 1.27 1.27)
				)
			)
		)
		(duplicate_pad_numbers_are_jumpers no)
		(fp_line
			(start 0.7874 0.4064)
			(end -0.7874 0.4064)
			(stroke
				(width 0.1524)
				(type default)
			)
			(layer "F.SilkS")
		)
		(fp_line
			(start 0.7874 -0.4064)
			(end 0.7874 0.4064)
			(stroke
				(width 0.1524)
				(type default)
			)
			(layer "F.SilkS")
		)
		(fp_line
			(start -0.7874 0.4064)
			(end -0.7874 -0.4064)
			(stroke
				(width 0.1524)
				(type default)
			)
			(layer "F.SilkS")
		)
		(fp_line
			(start -0.7874 -0.4064)
			(end 0.7874 -0.4064)
			(stroke
				(width 0.1524)
				(type default)
			)
			(layer "F.SilkS")
		)
		(fp_line
			(start 0.67945 0.3048)
			(end 0.120396 0.3048)
			(stroke
				(width 0.1)
				(type default)
			)
			(layer "F.Fab")
		)
		(fp_line
			(start 0.67945 -0.3048)
			(end 0.67945 0.3048)
			(stroke
				(width 0.1)
				(type default)
			)
			(layer "F.Fab")
		)
		(fp_line
			(start 0.12065 -0.2794)
			(end 0.12065 -0.3048)
			(stroke
				(width 0.1)
				(type default)
			)
			(layer "F.Fab")
		)
		(fp_line
			(start 0.12065 -0.3048)
			(end 0.67945 -0.3048)
			(stroke
				(width 0.1)
				(type default)
			)
			(layer "F.Fab")
		)
		(fp_line
			(start 0.120396 0.3048)
			(end 0.120396 0.2794)
			(stroke
				(width 0.1)
				(type default)
			)
			(layer "F.Fab")
		)
		(fp_line
			(start 0.120396 0.2794)
			(end -0.12065 0.2794)
			(stroke
				(width 0.1)
				(type default)
			)
			(layer "F.Fab")
		)
		(fp_line
			(start -0.12065 0.3048)
			(end -0.67945 0.3048)
			(stroke
				(width 0.1)
				(type default)
			)
			(layer "F.Fab")
		)
		(fp_line
			(start -0.12065 0.2794)
			(end -0.12065 0.3048)
			(stroke
				(width 0.1)
				(type default)
			)
			(layer "F.Fab")
		)
		(fp_line
			(start -0.12065 -0.2794)
			(end 0.12065 -0.2794)
			(stroke
				(width 0.1)
				(type default)
			)
			(layer "F.Fab")
		)
		(fp_line
			(start -0.12065 -0.305054)
			(end -0.12065 -0.2794)
			(stroke
				(width 0.1)
				(type default)
			)
			(layer "F.Fab")
		)
		(fp_line
			(start -0.67945 0.3048)
			(end -0.67945 -0.305054)
			(stroke
				(width 0.1)
				(type default)
			)
			(layer "F.Fab")
		)
		(fp_line
			(start -0.67945 -0.305054)
			(end -0.12065 -0.305054)
			(stroke
				(width 0.1)
				(type default)
			)
			(layer "F.Fab")
		)
		(pad "1" smd circle
			(at -0.40005 0 180)
			(size 0 0)
			(layers "F.Cu" "F.Mask" "F.Paste")
			(net "PRSNT_SSD7_FPGA_PCA9555_N")
		)
		(pad "2" smd circle
			(at 0.40005 0 180)
			(size 0 0)
			(layers "F.Cu" "F.Mask" "F.Paste")
			(net "PRSNT_SSD7_FPGA_R_N")
		)
	)
	(footprint ""
		(layer "F.Cu")
		(at 179.98186 -184.9247)
		(property "Reference" "R6657"
			(at 0 0 0)
			(layer "F.SilkS")
			(hide yes)
			(effects
				(font
					(size 1.27 1.27)
				)
			)
		)
		(property "Value" ""
			(at 0 0 0)
			(layer "F.Fab")
			(effects
				(font
					(size 1.27 1.27)
				)
			)
		)
		(duplicate_pad_numbers_are_jumpers no)
		(fp_line
			(start -0.7874 -0.4064)
			(end 0.7874 -0.4064)
			(stroke
				(width 0.1524)
				(type default)
			)
			(layer "F.SilkS")
		)
		(fp_line
			(start -0.7874 0.4064)
			(end -0.7874 -0.4064)
			(stroke
				(width 0.1524)
				(type default)
			)
			(layer "F.SilkS")
		)
		(fp_line
			(start 0.7874 -0.4064)
			(end 0.7874 0.4064)
			(stroke
				(width 0.1524)
				(type default)
			)
			(layer "F.SilkS")
		)
		(fp_line
			(start 0.7874 0.4064)
			(end -0.7874 0.4064)
			(stroke
				(width 0.1524)
				(type default)
			)
			(layer "F.SilkS")
		)
		(fp_line
			(start -0.67945 -0.305054)
			(end -0.12065 -0.305054)
			(stroke
				(width 0.1)
				(type default)
			)
			(layer "F.Fab")
		)
		(fp_line
			(start -0.67945 0.3048)
			(end -0.67945 -0.305054)
			(stroke
				(width 0.1)
				(type default)
			)
			(layer "F.Fab")
		)
		(fp_line
			(start -0.12065 -0.305054)
			(end -0.12065 -0.2794)
			(stroke
				(width 0.1)
				(type default)
			)
			(layer "F.Fab")
		)
		(fp_line
			(start -0.12065 -0.2794)
			(end 0.12065 -0.2794)
			(stroke
				(width 0.1)
				(type default)
			)
			(layer "F.Fab")
		)
		(fp_line
			(start -0.12065 0.2794)
			(end -0.12065 0.3048)
			(stroke
				(width 0.1)
				(type default)
			)
			(layer "F.Fab")
		)
		(fp_line
			(start -0.12065 0.3048)
			(end -0.67945 0.3048)
			(stroke
				(width 0.1)
				(type default)
			)
			(layer "F.Fab")
		)
		(fp_line
			(start 0.120396 0.2794)
			(end -0.12065 0.2794)
			(stroke
				(width 0.1)
				(type default)
			)
			(layer "F.Fab")
		)
		(fp_line
			(start 0.120396 0.3048)
			(end 0.120396 0.2794)
			(stroke
				(width 0.1)
				(type default)
			)
			(layer "F.Fab")
		)
		(fp_line
			(start 0.12065 -0.3048)
			(end 0.67945 -0.3048)
			(stroke
				(width 0.1)
				(type default)
			)
			(layer "F.Fab")
		)
		(fp_line
			(start 0.12065 -0.2794)
			(end 0.12065 -0.3048)
			(stroke
				(width 0.1)
				(type default)
			)
			(layer "F.Fab")
		)
		(fp_line
			(start 0.67945 -0.3048)
			(end 0.67945 0.3048)
			(stroke
				(width 0.1)
				(type default)
			)
			(layer "F.Fab")
		)
		(fp_line
			(start 0.67945 0.3048)
			(end 0.120396 0.3048)
			(stroke
				(width 0.1)
				(type default)
			)
			(layer "F.Fab")
		)
		(pad "1" smd circle
			(at -0.40005 0)
			(size 0 0)
			(layers "F.Cu" "F.Mask" "F.Paste")
			(net "SPI_BIC1_LS01_EN_N")
		)
		(pad "2" smd circle
			(at 0.40005 0)
			(size 0 0)
			(layers "F.Cu" "F.Mask" "F.Paste")
			(net "P1V8_PEX")
		)
	)
	(footprint ""
		(layer "F.Cu")
		(at 231.844596 -276.519386)
		(property "Reference" "R785"
			(at 0 0 0)
			(layer "F.SilkS")
			(hide yes)
			(effects
				(font
					(size 1.27 1.27)
				)
			)
		)
		(property "Value" ""
			(at 0 0 0)
			(layer "F.Fab")
			(effects
				(font
					(size 1.27 1.27)
				)
			)
		)
		(duplicate_pad_numbers_are_jumpers no)
		(fp_line
			(start -0.7874 -0.4064)
			(end 0.7874 -0.4064)
			(stroke
				(width 0.1524)
				(type default)
			)
			(layer "F.SilkS")
		)
		(fp_line
			(start -0.7874 0.4064)
			(end -0.7874 -0.4064)
			(stroke
				(width 0.1524)
				(type default)
			)
			(layer "F.SilkS")
		)
		(fp_line
			(start 0.7874 -0.4064)
			(end 0.7874 0.4064)
			(stroke
				(width 0.1524)
				(type default)
			)
			(layer "F.SilkS")
		)
		(fp_line
			(start 0.7874 0.4064)
			(end -0.7874 0.4064)
			(stroke
				(width 0.1524)
				(type default)
			)
			(layer "F.SilkS")
		)
		(fp_line
			(start -0.67945 -0.305054)
			(end -0.12065 -0.305054)
			(stroke
				(width 0.1)
				(type default)
			)
			(layer "F.Fab")
		)
		(fp_line
			(start -0.67945 0.3048)
			(end -0.67945 -0.305054)
			(stroke
				(width 0.1)
				(type default)
			)
			(layer "F.Fab")
		)
		(fp_line
			(start -0.12065 -0.305054)
			(end -0.12065 -0.2794)
			(stroke
				(width 0.1)
				(type default)
			)
			(layer "F.Fab")
		)
		(fp_line
			(start -0.12065 -0.2794)
			(end 0.12065 -0.2794)
			(stroke
				(width 0.1)
				(type default)
			)
			(layer "F.Fab")
		)
		(fp_line
			(start -0.12065 0.2794)
			(end -0.12065 0.3048)
			(stroke
				(width 0.1)
				(type default)
			)
			(layer "F.Fab")
		)
		(fp_line
			(start -0.12065 0.3048)
			(end -0.67945 0.3048)
			(stroke
				(width 0.1)
				(type default)
			)
			(layer "F.Fab")
		)
		(fp_line
			(start 0.120396 0.2794)
			(end -0.12065 0.2794)
			(stroke
				(width 0.1)
				(type default)
			)
			(layer "F.Fab")
		)
		(fp_line
			(start 0.120396 0.3048)
			(end 0.120396 0.2794)
			(stroke
				(width 0.1)
				(type default)
			)
			(layer "F.Fab")
		)
		(fp_line
			(start 0.12065 -0.3048)
			(end 0.67945 -0.3048)
			(stroke
				(width 0.1)
				(type default)
			)
			(layer "F.Fab")
		)
		(fp_line
			(start 0.12065 -0.2794)
			(end 0.12065 -0.3048)
			(stroke
				(width 0.1)
				(type default)
			)
			(layer "F.Fab")
		)
		(fp_line
			(start 0.67945 -0.3048)
			(end 0.67945 0.3048)
			(stroke
				(width 0.1)
				(type default)
			)
			(layer "F.Fab")
		)
		(fp_line
			(start 0.67945 0.3048)
			(end 0.120396 0.3048)
			(stroke
				(width 0.1)
				(type default)
			)
			(layer "F.Fab")
		)
		(pad "1" smd circle
			(at -0.40005 0)
			(size 0 0)
			(layers "F.Cu" "F.Mask" "F.Paste")
			(net "PEX1_P1V25_ADC_A0")
		)
		(pad "2" smd circle
			(at 0.40005 0)
			(size 0 0)
			(layers "F.Cu" "F.Mask" "F.Paste")
			(net "GND")
		)
	)
	(footprint ""
		(layer "F.Cu")
		(at 265.823954 -238.454184)
		(property "Reference" "ME8"
			(at -0.0762 -7.441438 0)
			(unlocked yes)
			(layer "F.SilkS")
			(effects
				(font
					(size 0.7874 0.5842)
					(thickness 0.1524)
				)
				(justify left)
			)
		)
		(property "Value" ""
			(at 0 0 0)
			(layer "F.Fab")
			(effects
				(font
					(size 1.27 1.27)
				)
			)
		)
		(duplicate_pad_numbers_are_jumpers no)
		(fp_line
			(start 0 -6.500114)
			(end 0 -4.976114)
			(stroke
				(width 0.1524)
				(type default)
			)
			(layer "F.SilkS")
		)
		(fp_line
			(start 0 -1.524)
			(end 0 0)
			(stroke
				(width 0.1524)
				(type default)
			)
			(layer "F.SilkS")
		)
		(fp_line
			(start 0 0)
			(end 1.524 0)
			(stroke
				(width 0.1524)
				(type default)
			)
			(layer "F.SilkS")
		)
		(fp_line
			(start 1.524 -6.500114)
			(end 0 -6.500114)
			(stroke
				(width 0.1524)
				(type default)
			)
			(layer "F.SilkS")
		)
		(fp_line
			(start 37.976048 -6.500114)
			(end 39.500048 -6.500114)
			(stroke
				(width 0.1524)
				(type default)
			)
			(layer "F.SilkS")
		)
		(fp_line
			(start 39.500048 -6.500114)
			(end 39.500048 -4.976114)
			(stroke
				(width 0.1524)
				(type default)
			)
			(layer "F.SilkS")
		)
		(fp_line
			(start 39.500048 -1.524)
			(end 39.500048 0)
			(stroke
				(width 0.1524)
				(type default)
			)
			(layer "F.SilkS")
		)
		(fp_line
			(start 39.500048 0)
			(end 37.976048 0)
			(stroke
				(width 0.1524)
				(type default)
			)
			(layer "F.SilkS")
		)
		(fp_text user "Rework version"
			(at 6.656324 -3.15468 0)
			(unlocked yes)
			(layer "F.SilkS")
			(effects
				(font
					(size 1.905 1.4224)
					(thickness 0.1524)
				)
				(justify left)
			)
		)
	)
	(footprint ""
		(layer "F.Cu")
		(at 89.327482 -343.952322 90)
		(property "Reference" "C101"
			(at 0 0 90)
			(layer "F.SilkS")
			(hide yes)
			(effects
				(font
					(size 1.27 1.27)
				)
			)
		)
		(property "Value" ""
			(at 0 0 90)
			(layer "F.Fab")
			(effects
				(font
					(size 1.27 1.27)
				)
			)
		)
		(duplicate_pad_numbers_are_jumpers no)
		(fp_line
			(start 0.299974 -0.150114)
			(end 0.299974 0.150114)
			(stroke
				(width 0.1)
				(type default)
			)
			(layer "F.Fab")
		)
		(fp_line
			(start -0.299974 -0.150114)
			(end 0.299974 -0.150114)
			(stroke
				(width 0.1)
				(type default)
			)
			(layer "F.Fab")
		)
		(fp_line
			(start 0.299974 0.150114)
			(end -0.299974 0.150114)
			(stroke
				(width 0.1)
				(type default)
			)
			(layer "F.Fab")
		)
		(fp_line
			(start -0.299974 0.150114)
			(end -0.299974 -0.150114)
			(stroke
				(width 0.1)
				(type default)
			)
			(layer "F.Fab")
		)
		(pad "1" smd rect
			(at -0.2667 0 90)
			(size 0.3048 0.381)
			(layers "F.Cu" "F.Mask" "F.Paste")
			(net "P5E_PEX0_STN5_TX_DP<93>")
		)
		(pad "2" smd rect
			(at 0.2667 0 90)
			(size 0.3048 0.381)
			(layers "F.Cu" "F.Mask" "F.Paste")
			(net "P5E_PEX0_STN5_TX_C_DP<93>")
		)
	)
	(footprint ""
		(layer "F.Cu")
		(at 57.656222 -61.487812 180)
		(property "Reference" "R5846"
			(at 0 0 180)
			(layer "F.SilkS")
			(hide yes)
			(effects
				(font
					(size 1.27 1.27)
				)
			)
		)
		(property "Value" ""
			(at 0 0 180)
			(layer "F.Fab")
			(effects
				(font
					(size 1.27 1.27)
				)
			)
		)
		(duplicate_pad_numbers_are_jumpers no)
		(fp_line
			(start 0.7874 0.4064)
			(end -0.7874 0.4064)
			(stroke
				(width 0.1524)
				(type default)
			)
			(layer "F.SilkS")
		)
		(fp_line
			(start 0.7874 -0.4064)
			(end 0.7874 0.4064)
			(stroke
				(width 0.1524)
				(type default)
			)
			(layer "F.SilkS")
		)
		(fp_line
			(start -0.7874 0.4064)
			(end -0.7874 -0.4064)
			(stroke
				(width 0.1524)
				(type default)
			)
			(layer "F.SilkS")
		)
		(fp_line
			(start -0.7874 -0.4064)
			(end 0.7874 -0.4064)
			(stroke
				(width 0.1524)
				(type default)
			)
			(layer "F.SilkS")
		)
		(fp_line
			(start 0.67945 0.3048)
			(end 0.120396 0.3048)
			(stroke
				(width 0.1)
				(type default)
			)
			(layer "F.Fab")
		)
		(fp_line
			(start 0.67945 -0.3048)
			(end 0.67945 0.3048)
			(stroke
				(width 0.1)
				(type default)
			)
			(layer "F.Fab")
		)
		(fp_line
			(start 0.12065 -0.2794)
			(end 0.12065 -0.3048)
			(stroke
				(width 0.1)
				(type default)
			)
			(layer "F.Fab")
		)
		(fp_line
			(start 0.12065 -0.3048)
			(end 0.67945 -0.3048)
			(stroke
				(width 0.1)
				(type default)
			)
			(layer "F.Fab")
		)
		(fp_line
			(start 0.120396 0.3048)
			(end 0.120396 0.2794)
			(stroke
				(width 0.1)
				(type default)
			)
			(layer "F.Fab")
		)
		(fp_line
			(start 0.120396 0.2794)
			(end -0.12065 0.2794)
			(stroke
				(width 0.1)
				(type default)
			)
			(layer "F.Fab")
		)
		(fp_line
			(start -0.12065 0.3048)
			(end -0.67945 0.3048)
			(stroke
				(width 0.1)
				(type default)
			)
			(layer "F.Fab")
		)
		(fp_line
			(start -0.12065 0.2794)
			(end -0.12065 0.3048)
			(stroke
				(width 0.1)
				(type default)
			)
			(layer "F.Fab")
		)
		(fp_line
			(start -0.12065 -0.2794)
			(end 0.12065 -0.2794)
			(stroke
				(width 0.1)
				(type default)
			)
			(layer "F.Fab")
		)
		(fp_line
			(start -0.12065 -0.305054)
			(end -0.12065 -0.2794)
			(stroke
				(width 0.1)
				(type default)
			)
			(layer "F.Fab")
		)
		(fp_line
			(start -0.67945 0.3048)
			(end -0.67945 -0.305054)
			(stroke
				(width 0.1)
				(type default)
			)
			(layer "F.Fab")
		)
		(fp_line
			(start -0.67945 -0.305054)
			(end -0.12065 -0.305054)
			(stroke
				(width 0.1)
				(type default)
			)
			(layer "F.Fab")
		)
		(pad "1" smd circle
			(at -0.40005 0 180)
			(size 0 0)
			(layers "F.Cu" "F.Mask" "F.Paste")
			(net "P3V3_AUX")
		)
		(pad "2" smd circle
			(at 0.40005 0 180)
			(size 0 0)
			(layers "F.Cu" "F.Mask" "F.Paste")
			(net "PWRGD_P12V_SSD2_D")
		)
	)
)
